# T6G (Grand Teton) — schematic netlist excerpt (pin names and nets, part order shuffled) for the footprints in the layout excerpt that follows; sources: Cadence DE-HDL packaged netlist, KiCad conversion of 04192023_DAF0TMB3IC0_F0TG_MB_C_brd_V02_OCP.brd

R1358  Q_RES  10K 5% EMPTY  pkg 0402LF  page 167 : A = P1V8_AUX ; B = FM_PASSWORD_CLEAR_N
C2250  Q_CAP  22UF 4V 20% X6S  pkg C0402  page 69 : A = PVDDCR_CPU1_P0 ; B = GND

(kicad_pcb
	(version 20260206)
	(generator "pcbnew")
	(generator_version "10.0")
	(general
		(thickness 1.6)
		(legacy_teardrops no)
	)
	(paper "A4")
	(title_block
		(title "04192023_DAF0TMB3IC0_F0TG_MB_C_brd_V02_OCP.brd")
		(comment 1 "Grand Teton / footprints 5031-5032 of 8354")
	)
	(layers
		(0 "F.Cu" signal "TOP")
		(4 "In1.Cu" signal "GND")
		(6 "In2.Cu" signal "IN1")
		(8 "In3.Cu" signal "GND1")
		(10 "In4.Cu" signal "IN2")
		(12 "In5.Cu" signal "GND2")
		(14 "In6.Cu" signal "IN3")
		(16 "In7.Cu" signal "GND3")
		(18 "In8.Cu" signal "VCC")
		(20 "In9.Cu" signal "VCC1")
		(22 "In10.Cu" signal "GND4")
		(24 "In11.Cu" signal "IN4")
		(26 "In12.Cu" signal "GND5")
		(28 "In13.Cu" signal "IN5")
		(30 "In14.Cu" signal "GND6")
		(32 "In15.Cu" signal "IN6")
		(34 "In16.Cu" signal "GND7")
		(2 "B.Cu" signal "BOTTOM")
		(9 "F.Adhes" user "F.Adhesive")
		(11 "B.Adhes" user "B.Adhesive")
		(13 "F.Paste" user "Package Geometry/Pastemask Top")
		(15 "B.Paste" user "Package Geometry/Pastemask Bottom")
		(5 "F.SilkS" user "Ref Des/Silkscreen Top")
		(7 "B.SilkS" user "Ref Des/Silkscreen Bottom")
		(1 "F.Mask" user "Board Geometry/Soldermask Top")
		(3 "B.Mask" user "Board Geometry/Soldermask Bottom")
		(17 "Dwgs.User" user "User.Drawings")
		(19 "Cmts.User" user "User.Comments")
		(21 "Eco1.User" user "User.Eco1")
		(23 "Eco2.User" user "User.Eco2")
		(25 "Edge.Cuts" user "Board Geometry/Outline")
		(27 "Margin" user)
		(31 "F.CrtYd" user "Package Geometry/Place Bound Top")
		(29 "B.CrtYd" user "Package Geometry/Place Bound Bottom")
		(35 "F.Fab" user "Ref Des/Assembly Top")
		(33 "B.Fab" user "Ref Des/Assembly Bottom")
	)
	(footprint ""
		(layer "B.Cu")
		(at 428.98695 -32.197548 180)
		(property "Reference" "R1358"
			(at 0 0 0)
			(layer "B.SilkS")
			(hide yes)
			(effects
				(font
					(size 1.27 1.27)
				)
				(justify mirror)
			)
		)
		(property "Value" ""
			(at 0 0 0)
			(layer "B.Fab")
			(effects
				(font
					(size 1.27 1.27)
				)
				(justify mirror)
			)
		)
		(duplicate_pad_numbers_are_jumpers no)
		(fp_line
			(start 0.7874 0.4064)
			(end 0.7874 -0.4064)
			(stroke
				(width 0.1524)
				(type default)
			)
			(layer "B.SilkS")
		)
		(fp_line
			(start 0.7874 -0.4064)
			(end -0.7874 -0.4064)
			(stroke
				(width 0.1524)
				(type default)
			)
			(layer "B.SilkS")
		)
		(fp_line
			(start -0.7874 0.4064)
			(end 0.7874 0.4064)
			(stroke
				(width 0.1524)
				(type default)
			)
			(layer "B.SilkS")
		)
		(fp_line
			(start -0.7874 -0.4064)
			(end -0.7874 0.4064)
			(stroke
				(width 0.1524)
				(type default)
			)
			(layer "B.SilkS")
		)
		(fp_line
			(start 0.67945 0.3048)
			(end 0.67945 -0.305054)
			(stroke
				(width 0.1)
				(type default)
			)
			(layer "B.Fab")
		)
		(fp_line
			(start 0.67945 -0.305054)
			(end 0.12065 -0.305054)
			(stroke
				(width 0.1)
				(type default)
			)
			(layer "B.Fab")
		)
		(fp_line
			(start 0.12065 0.3048)
			(end 0.67945 0.3048)
			(stroke
				(width 0.1)
				(type default)
			)
			(layer "B.Fab")
		)
		(fp_line
			(start 0.12065 0.2794)
			(end 0.12065 0.3048)
			(stroke
				(width 0.1)
				(type default)
			)
			(layer "B.Fab")
		)
		(fp_line
			(start 0.12065 -0.2794)
			(end -0.12065 -0.2794)
			(stroke
				(width 0.1)
				(type default)
			)
			(layer "B.Fab")
		)
		(fp_line
			(start 0.12065 -0.305054)
			(end 0.12065 -0.2794)
			(stroke
				(width 0.1)
				(type default)
			)
			(layer "B.Fab")
		)
		(fp_line
			(start -0.120396 0.3048)
			(end -0.120396 0.2794)
			(stroke
				(width 0.1)
				(type default)
			)
			(layer "B.Fab")
		)
		(fp_line
			(start -0.120396 0.2794)
			(end 0.12065 0.2794)
			(stroke
				(width 0.1)
				(type default)
			)
			(layer "B.Fab")
		)
		(fp_line
			(start -0.12065 -0.2794)
			(end -0.12065 -0.3048)
			(stroke
				(width 0.1)
				(type default)
			)
			(layer "B.Fab")
		)
		(fp_line
			(start -0.12065 -0.3048)
			(end -0.67945 -0.3048)
			(stroke
				(width 0.1)
				(type default)
			)
			(layer "B.Fab")
		)
		(fp_line
			(start -0.67945 0.3048)
			(end -0.120396 0.3048)
			(stroke
				(width 0.1)
				(type default)
			)
			(layer "B.Fab")
		)
		(fp_line
			(start -0.67945 -0.3048)
			(end -0.67945 0.3048)
			(stroke
				(width 0.1)
				(type default)
			)
			(layer "B.Fab")
		)
		(pad "1" smd circle
			(at 0.40005 0)
			(size 0 0)
			(layers "B.Cu" "B.Mask" "B.Paste")
			(net "P1V8_AUX")
		)
		(pad "2" smd circle
			(at -0.40005 0)
			(size 0 0)
			(layers "B.Cu" "B.Mask" "B.Paste")
			(net "FM_PASSWORD_CLEAR_N")
		)
	)
	(footprint ""
		(layer "B.Cu")
		(at 353.485958 -272.284952)
		(property "Reference" "C2250"
			(at 0 0 0)
			(layer "B.SilkS")
			(hide yes)
			(effects
				(font
					(size 1.27 1.27)
				)
				(justify mirror)
			)
		)
		(property "Value" ""
			(at 0 0 0)
			(layer "B.Fab")
			(effects
				(font
					(size 1.27 1.27)
				)
				(justify mirror)
			)
		)
		(duplicate_pad_numbers_are_jumpers no)
		(fp_line
			(start -0.7874 -0.4064)
			(end -0.7874 0.4064)
			(stroke
				(width 0.1524)
				(type default)
			)
			(layer "B.SilkS")
		)
		(fp_line
			(start -0.7874 0.4064)
			(end 0.7874 0.4064)
			(stroke
				(width 0.1524)
				(type default)
			)
			(layer "B.SilkS")
		)
		(fp_line
			(start 0.7874 -0.4064)
			(end -0.7874 -0.4064)
			(stroke
				(width 0.1524)
				(type default)
			)
			(layer "B.SilkS")
		)
		(fp_line
			(start 0.7874 0.4064)
			(end 0.7874 -0.4064)
			(stroke
				(width 0.1524)
				(type default)
			)
			(layer "B.SilkS")
		)
		(fp_line
			(start -0.67945 -0.3048)
			(end -0.67945 0.3048)
			(stroke
				(width 0.1)
				(type default)
			)
			(layer "B.Fab")
		)
		(fp_line
			(start -0.67945 0.3048)
			(end -0.120396 0.3048)
			(stroke
				(width 0.1)
				(type default)
			)
			(layer "B.Fab")
		)
		(fp_line
			(start -0.12065 -0.3048)
			(end -0.67945 -0.3048)
			(stroke
				(width 0.1)
				(type default)
			)
			(layer "B.Fab")
		)
		(fp_line
			(start -0.12065 -0.2794)
			(end -0.12065 -0.3048)
			(stroke
				(width 0.1)
				(type default)
			)
			(layer "B.Fab")
		)
		(fp_line
			(start -0.120396 0.2794)
			(end 0.12065 0.2794)
			(stroke
				(width 0.1)
				(type default)
			)
			(layer "B.Fab")
		)
		(fp_line
			(start -0.120396 0.3048)
			(end -0.120396 0.2794)
			(stroke
				(width 0.1)
				(type default)
			)
			(layer "B.Fab")
		)
		(fp_line
			(start 0.12065 -0.305054)
			(end 0.12065 -0.2794)
			(stroke
				(width 0.1)
				(type default)
			)
			(layer "B.Fab")
		)
		(fp_line
			(start 0.12065 -0.2794)
			(end -0.12065 -0.2794)
			(stroke
				(width 0.1)
				(type default)
			)
			(layer "B.Fab")
		)
		(fp_line
			(start 0.12065 0.2794)
			(end 0.12065 0.3048)
			(stroke
				(width 0.1)
				(type default)
			)
			(layer "B.Fab")
		)
		(fp_line
			(start 0.12065 0.3048)
			(end 0.67945 0.3048)
			(stroke
				(width 0.1)
				(type default)
			)
			(layer "B.Fab")
		)
		(fp_line
			(start 0.67945 -0.305054)
			(end 0.12065 -0.305054)
			(stroke
				(width 0.1)
				(type default)
			)
			(layer "B.Fab")
		)
		(fp_line
			(start 0.67945 0.3048)
			(end 0.67945 -0.305054)
			(stroke
				(width 0.1)
				(type default)
			)
			(layer "B.Fab")
		)
		(pad "1" smd circle
			(at 0.40005 0 180)
			(size 0 0)
			(layers "B.Cu" "B.Mask" "B.Paste")
			(net "PVDDCR_CPU1_P0")
		)
		(pad "2" smd circle
			(at -0.40005 0 180)
			(size 0 0)
			(layers "B.Cu" "B.Mask" "B.Paste")
			(net "GND")
		)
	)
)
